(kicad_pcb
	(version 20221018)
	(generator pcbnew)
	(general
    (thickness 1.62)
  )
	(paper "A4")
	(title_block
    (title "ECP5 - Datacenter Secure Control Module (DC-SCM)")
    (date "2024-07-01")
    (rev "1.2.1")
		(comment 9 "footprint 50 of 506 (U21), pads 493-596 of 756")
	)
	(layers
    (0 "F.Cu" signal)
    (1 "In1.Cu" power)
    (2 "In2.Cu" signal)
    (3 "In3.Cu" power)
    (4 "In4.Cu" power)
    (5 "In5.Cu" signal)
    (6 "In6.Cu" power)
    (31 "B.Cu" signal)
    (32 "B.Adhes" user "B.Adhesive")
    (33 "F.Adhes" user "F.Adhesive")
    (34 "B.Paste" user)
    (35 "F.Paste" user)
    (36 "B.SilkS" user "B.Silkscreen")
    (37 "F.SilkS" user "F.Silkscreen")
    (38 "B.Mask" user)
    (39 "F.Mask" user)
    (40 "Dwgs.User" user "User.Drawings")
    (41 "Cmts.User" user "User.Comments")
    (42 "Eco1.User" user "User.Eco1")
    (43 "Eco2.User" user "User.Eco2")
    (44 "Edge.Cuts" user)
    (45 "Margin" user)
    (46 "B.CrtYd" user "B.Courtyard")
    (47 "F.CrtYd" user "F.Courtyard")
    (48 "B.Fab" user)
    (49 "F.Fab" user)
  )
	(footprint "antmicro-footprints:BGA-1024-756_27x27mm_Layout32x32_P0.8mm" locked
    (layer "F.Cu")
    (at 104.4 120.55)
    (property "Author" "Antmicro")
    (property "License" "Apache-2.0")
    (property "MPN" "LFE5UM5G-85F-8BG756C")
    (property "Manufacturer" "Lattice Semiconductor")
    (property "Sheetfile" "fpga-power-supply.kicad_sch")
    (property "Sheetname" "FPGA power supply")
    (property "ki_description" "ECP5-5G Field Programmable Gate Array")
    (property "ki_keywords" "SMT, FPGA, IC")
    (attr smd)
    (fp_text reference "U21" (at -12.97 -14.53) (layer "F.SilkS")
        (effects (font (size 0.7 0.7) (thickness 0.127)))
    )
    (fp_text value "ECP5UM5G_85_CABGA756" (at 0 14.5) (layer "F.Fab")
        (effects (font (size 1 1) (thickness 0.15)))
    )
    (pad "L1" smd circle locked (at -12.4 -4.4) (size 0.4 0.4) (layers "F.Cu" "F.Paste" "F.Mask")
      (net 731 "unconnected-(U21H-PL29D-PadL1)") (pinfunction "PL29D") (pintype "bidirectional+no_connect"))
    (pad "L2" smd circle locked (at -11.6 -4.4) (size 0.4 0.4) (layers "F.Cu" "F.Paste" "F.Mask")
      (net 732 "unconnected-(U21H-PL32A-PadL2)") (pinfunction "PL32A") (pintype "bidirectional+no_connect"))
    (pad "L3" smd circle locked (at -10.8 -4.4) (size 0.4 0.4) (layers "F.Cu" "F.Paste" "F.Mask")
      (net 377 "MMC_RSTN") (pinfunction "PL32B") (pintype "bidirectional"))
    (pad "L4" smd circle locked (at -10 -4.4) (size 0.4 0.4) (layers "F.Cu" "F.Paste" "F.Mask")
      (net 282 "MMC_DAT3") (pinfunction "PL38D") (pintype "bidirectional"))
    (pad "L5" smd circle locked (at -9.2 -4.4) (size 0.4 0.4) (layers "F.Cu" "F.Paste" "F.Mask")
      (net 733 "unconnected-(U21A-NC-PadL5)") (pinfunction "NC") (pintype "no_connect"))
    (pad "L6" smd circle locked (at -8.4 -4.4) (size 0.4 0.4) (layers "F.Cu" "F.Paste" "F.Mask")
      (net 734 "unconnected-(U21H-PL41D-PadL6)") (pinfunction "PL41D") (pintype "bidirectional+no_connect"))
    (pad "L7" smd circle locked (at -7.6 -4.4) (size 0.4 0.4) (layers "F.Cu" "F.Paste" "F.Mask")
      (net 280 "MMC_DAT1") (pinfunction "PL41C") (pintype "bidirectional"))
    (pad "L10" smd circle locked (at -5.2 -4.4) (size 0.4 0.4) (layers "F.Cu" "F.Paste" "F.Mask")
      (net 1 "GND") (pinfunction "GND") (pintype "passive"))
    (pad "L11" smd circle locked (at -4.4 -4.4) (size 0.4 0.4) (layers "F.Cu" "F.Paste" "F.Mask")
      (net 1 "GND") (pinfunction "GND") (pintype "passive"))
    (pad "L12" smd circle locked (at -3.6 -4.4) (size 0.4 0.4) (layers "F.Cu" "F.Paste" "F.Mask")
      (net 1 "GND") (pinfunction "GND") (pintype "passive"))
    (pad "L13" smd circle locked (at -2.8 -4.4) (size 0.4 0.4) (layers "F.Cu" "F.Paste" "F.Mask")
      (net 1 "GND") (pinfunction "GND") (pintype "passive"))
    (pad "L14" smd circle locked (at -2 -4.4) (size 0.4 0.4) (layers "F.Cu" "F.Paste" "F.Mask")
      (net 1 "GND") (pinfunction "GND") (pintype "passive"))
    (pad "L15" smd circle locked (at -1.2 -4.4) (size 0.4 0.4) (layers "F.Cu" "F.Paste" "F.Mask")
      (net 1 "GND") (pinfunction "GND") (pintype "passive"))
    (pad "L16" smd circle locked (at -0.4 -4.4) (size 0.4 0.4) (layers "F.Cu" "F.Paste" "F.Mask")
      (net 1 "GND") (pinfunction "GND") (pintype "passive"))
    (pad "L17" smd circle locked (at 0.4 -4.4) (size 0.4 0.4) (layers "F.Cu" "F.Paste" "F.Mask")
      (net 1 "GND") (pinfunction "GND") (pintype "passive"))
    (pad "L18" smd circle locked (at 1.2 -4.4) (size 0.4 0.4) (layers "F.Cu" "F.Paste" "F.Mask")
      (net 1 "GND") (pinfunction "GND") (pintype "passive"))
    (pad "L19" smd circle locked (at 2 -4.4) (size 0.4 0.4) (layers "F.Cu" "F.Paste" "F.Mask")
      (net 1 "GND") (pinfunction "GND") (pintype "passive"))
    (pad "L20" smd circle locked (at 2.8 -4.4) (size 0.4 0.4) (layers "F.Cu" "F.Paste" "F.Mask")
      (net 1 "GND") (pinfunction "GND") (pintype "passive"))
    (pad "L21" smd circle locked (at 3.6 -4.4) (size 0.4 0.4) (layers "F.Cu" "F.Paste" "F.Mask")
      (net 1 "GND") (pinfunction "GND") (pintype "passive"))
    (pad "L22" smd circle locked (at 4.4 -4.4) (size 0.4 0.4) (layers "F.Cu" "F.Paste" "F.Mask")
      (net 1 "GND") (pinfunction "GND") (pintype "passive"))
    (pad "L23" smd circle locked (at 5.2 -4.4) (size 0.4 0.4) (layers "F.Cu" "F.Paste" "F.Mask")
      (net 1 "GND") (pinfunction "GND") (pintype "passive"))
    (pad "L26" smd circle locked (at 7.6 -4.4) (size 0.4 0.4) (layers "F.Cu" "F.Paste" "F.Mask")
      (net 735 "unconnected-(U21D-PR41C-PadL26)") (pinfunction "PR41C") (pintype "bidirectional+no_connect"))
    (pad "L27" smd circle locked (at 8.4 -4.4) (size 0.4 0.4) (layers "F.Cu" "F.Paste" "F.Mask")
      (net 736 "unconnected-(U21D-PR41D-PadL27)") (pinfunction "PR41D") (pintype "bidirectional+no_connect"))
    (pad "L28" smd circle locked (at 9.2 -4.4) (size 0.4 0.4) (layers "F.Cu" "F.Paste" "F.Mask")
      (net 737 "unconnected-(U21A-NC-PadL28)") (pinfunction "NC") (pintype "no_connect"))
    (pad "L29" smd circle locked (at 10 -4.4) (size 0.4 0.4) (layers "F.Cu" "F.Paste" "F.Mask")
      (net 738 "unconnected-(U21D-PR38D-PadL29)") (pinfunction "PR38D") (pintype "bidirectional+no_connect"))
    (pad "L30" smd circle locked (at 10.8 -4.4) (size 0.4 0.4) (layers "F.Cu" "F.Paste" "F.Mask")
      (net 739 "unconnected-(U21D-PR32B-PadL30)") (pinfunction "PR32B") (pintype "bidirectional+no_connect"))
    (pad "L31" smd circle locked (at 11.6 -4.4) (size 0.4 0.4) (layers "F.Cu" "F.Paste" "F.Mask")
      (net 59 "ESPI_CLK") (pinfunction "PR32A") (pintype "bidirectional"))
    (pad "L32" smd circle locked (at 12.4 -4.4) (size 0.4 0.4) (layers "F.Cu" "F.Paste" "F.Mask")
      (net 60 "ESPI_CS0_N") (pinfunction "PR29D") (pintype "bidirectional"))
    (pad "M10" smd circle locked (at -5.2 -3.6) (size 0.4 0.4) (layers "F.Cu" "F.Paste" "F.Mask")
      (net 2 "VCC3V3") (pinfunction "VCCIO7") (pintype "power_in"))
    (pad "M11" smd circle locked (at -4.4 -3.6) (size 0.4 0.4) (layers "F.Cu" "F.Paste" "F.Mask")
      (net 1 "GND") (pinfunction "GND") (pintype "passive"))
    (pad "M12" smd circle locked (at -3.6 -3.6) (size 0.4 0.4) (layers "F.Cu" "F.Paste" "F.Mask")
      (net 211 "VCC1V2") (pinfunction "VCC") (pintype "passive"))
    (pad "M13" smd circle locked (at -2.8 -3.6) (size 0.4 0.4) (layers "F.Cu" "F.Paste" "F.Mask")
      (net 211 "VCC1V2") (pinfunction "VCC") (pintype "passive"))
    (pad "M14" smd circle locked (at -2 -3.6) (size 0.4 0.4) (layers "F.Cu" "F.Paste" "F.Mask")
      (net 211 "VCC1V2") (pinfunction "VCC") (pintype "passive"))
    (pad "M15" smd circle locked (at -1.2 -3.6) (size 0.4 0.4) (layers "F.Cu" "F.Paste" "F.Mask")
      (net 211 "VCC1V2") (pinfunction "VCC") (pintype "passive"))
    (pad "M16" smd circle locked (at -0.4 -3.6) (size 0.4 0.4) (layers "F.Cu" "F.Paste" "F.Mask")
      (net 211 "VCC1V2") (pinfunction "VCC") (pintype "passive"))
    (pad "M17" smd circle locked (at 0.4 -3.6) (size 0.4 0.4) (layers "F.Cu" "F.Paste" "F.Mask")
      (net 211 "VCC1V2") (pinfunction "VCC") (pintype "passive"))
    (pad "M18" smd circle locked (at 1.2 -3.6) (size 0.4 0.4) (layers "F.Cu" "F.Paste" "F.Mask")
      (net 211 "VCC1V2") (pinfunction "VCC") (pintype "passive"))
    (pad "M19" smd circle locked (at 2 -3.6) (size 0.4 0.4) (layers "F.Cu" "F.Paste" "F.Mask")
      (net 211 "VCC1V2") (pinfunction "VCC") (pintype "passive"))
    (pad "M20" smd circle locked (at 2.8 -3.6) (size 0.4 0.4) (layers "F.Cu" "F.Paste" "F.Mask")
      (net 211 "VCC1V2") (pinfunction "VCC") (pintype "passive"))
    (pad "M21" smd circle locked (at 3.6 -3.6) (size 0.4 0.4) (layers "F.Cu" "F.Paste" "F.Mask")
      (net 211 "VCC1V2") (pinfunction "VCC") (pintype "passive"))
    (pad "M22" smd circle locked (at 4.4 -3.6) (size 0.4 0.4) (layers "F.Cu" "F.Paste" "F.Mask")
      (net 1 "GND") (pinfunction "GND") (pintype "passive"))
    (pad "M23" smd circle locked (at 5.2 -3.6) (size 0.4 0.4) (layers "F.Cu" "F.Paste" "F.Mask")
      (net 218 "VCC1V8") (pinfunction "VCCIO2") (pintype "power_in"))
    (pad "N1" smd circle locked (at -12.4 -2.8) (size 0.4 0.4) (layers "F.Cu" "F.Paste" "F.Mask")
      (net 740 "unconnected-(U21G-PL62A-PadN1)") (pinfunction "PL62A") (pintype "bidirectional+no_connect"))
    (pad "N2" smd circle locked (at -11.6 -2.8) (size 0.4 0.4) (layers "F.Cu" "F.Paste" "F.Mask")
      (net 1 "GND") (pinfunction "GND") (pintype "passive"))
    (pad "N3" smd circle locked (at -10.8 -2.8) (size 0.4 0.4) (layers "F.Cu" "F.Paste" "F.Mask")
      (net 281 "MMC_DAT2") (pinfunction "PL41A") (pintype "bidirectional"))
    (pad "N4" smd circle locked (at -10 -2.8) (size 0.4 0.4) (layers "F.Cu" "F.Paste" "F.Mask")
      (net 279 "MMC_DAT0") (pinfunction "PL41B") (pintype "bidirectional"))
    (pad "N5" smd circle locked (at -9.2 -2.8) (size 0.4 0.4) (layers "F.Cu" "F.Paste" "F.Mask")
      (net 1 "GND") (pinfunction "GND") (pintype "passive"))
    (pad "N6" smd circle locked (at -8.4 -2.8) (size 0.4 0.4) (layers "F.Cu" "F.Paste" "F.Mask")
      (net 367 "GCLK100") (pinfunction "PL44A") (pintype "bidirectional"))
    (pad "N7" smd circle locked (at -7.6 -2.8) (size 0.4 0.4) (layers "F.Cu" "F.Paste" "F.Mask")
      (net 741 "unconnected-(U21H-PL44B-PadN7)") (pinfunction "PL44B") (pintype "bidirectional+no_connect"))
    (pad "N10" smd circle locked (at -5.2 -2.8) (size 0.4 0.4) (layers "F.Cu" "F.Paste" "F.Mask")
      (net 304 "/FPGA power supply/VCCAUX") (pinfunction "VCCAUX") (pintype "passive"))
    (pad "N11" smd circle locked (at -4.4 -2.8) (size 0.4 0.4) (layers "F.Cu" "F.Paste" "F.Mask")
      (net 1 "GND") (pinfunction "GND") (pintype "passive"))
    (pad "N12" smd circle locked (at -3.6 -2.8) (size 0.4 0.4) (layers "F.Cu" "F.Paste" "F.Mask")
      (net 211 "VCC1V2") (pinfunction "VCC") (pintype "passive"))
    (pad "N13" smd circle locked (at -2.8 -2.8) (size 0.4 0.4) (layers "F.Cu" "F.Paste" "F.Mask")
      (net 1 "GND") (pinfunction "GND") (pintype "passive"))
    (pad "N14" smd circle locked (at -2 -2.8) (size 0.4 0.4) (layers "F.Cu" "F.Paste" "F.Mask")
      (net 1 "GND") (pinfunction "GND") (pintype "passive"))
    (pad "N15" smd circle locked (at -1.2 -2.8) (size 0.4 0.4) (layers "F.Cu" "F.Paste" "F.Mask")
      (net 1 "GND") (pinfunction "GND") (pintype "passive"))
    (pad "N16" smd circle locked (at -0.4 -2.8) (size 0.4 0.4) (layers "F.Cu" "F.Paste" "F.Mask")
      (net 1 "GND") (pinfunction "GND") (pintype "passive"))
    (pad "N17" smd circle locked (at 0.4 -2.8) (size 0.4 0.4) (layers "F.Cu" "F.Paste" "F.Mask")
      (net 1 "GND") (pinfunction "GND") (pintype "passive"))
    (pad "N18" smd circle locked (at 1.2 -2.8) (size 0.4 0.4) (layers "F.Cu" "F.Paste" "F.Mask")
      (net 1 "GND") (pinfunction "GND") (pintype "passive"))
    (pad "N19" smd circle locked (at 2 -2.8) (size 0.4 0.4) (layers "F.Cu" "F.Paste" "F.Mask")
      (net 1 "GND") (pinfunction "GND") (pintype "passive"))
    (pad "N20" smd circle locked (at 2.8 -2.8) (size 0.4 0.4) (layers "F.Cu" "F.Paste" "F.Mask")
      (net 1 "GND") (pinfunction "GND") (pintype "passive"))
    (pad "N21" smd circle locked (at 3.6 -2.8) (size 0.4 0.4) (layers "F.Cu" "F.Paste" "F.Mask")
      (net 211 "VCC1V2") (pinfunction "VCC") (pintype "passive"))
    (pad "N22" smd circle locked (at 4.4 -2.8) (size 0.4 0.4) (layers "F.Cu" "F.Paste" "F.Mask")
      (net 1 "GND") (pinfunction "GND") (pintype "passive"))
    (pad "N23" smd circle locked (at 5.2 -2.8) (size 0.4 0.4) (layers "F.Cu" "F.Paste" "F.Mask")
      (net 304 "/FPGA power supply/VCCAUX") (pinfunction "VCCAUX") (pintype "passive"))
    (pad "N26" smd circle locked (at 7.6 -2.8) (size 0.4 0.4) (layers "F.Cu" "F.Paste" "F.Mask")
      (net 742 "unconnected-(U21D-PR44B-PadN26)") (pinfunction "PR44B") (pintype "bidirectional+no_connect"))
    (pad "N27" smd circle locked (at 8.4 -2.8) (size 0.4 0.4) (layers "F.Cu" "F.Paste" "F.Mask")
      (net 743 "unconnected-(U21D-PR44A-PadN27)") (pinfunction "PR44A") (pintype "bidirectional+no_connect"))
    (pad "N28" smd circle locked (at 9.2 -2.8) (size 0.4 0.4) (layers "F.Cu" "F.Paste" "F.Mask")
      (net 1 "GND") (pinfunction "GND") (pintype "passive"))
    (pad "N29" smd circle locked (at 10 -2.8) (size 0.4 0.4) (layers "F.Cu" "F.Paste" "F.Mask")
      (net 744 "unconnected-(U21D-PR41B-PadN29)") (pinfunction "PR41B") (pintype "bidirectional+no_connect"))
    (pad "N30" smd circle locked (at 10.8 -2.8) (size 0.4 0.4) (layers "F.Cu" "F.Paste" "F.Mask")
      (net 745 "unconnected-(U21D-PR41A-PadN30)") (pinfunction "PR41A") (pintype "bidirectional+no_connect"))
    (pad "N31" smd circle locked (at 11.6 -2.8) (size 0.4 0.4) (layers "F.Cu" "F.Paste" "F.Mask")
      (net 1 "GND") (pinfunction "GND") (pintype "passive"))
    (pad "N32" smd circle locked (at 12.4 -2.8) (size 0.4 0.4) (layers "F.Cu" "F.Paste" "F.Mask")
      (net 331 "ULPI1_NXT") (pinfunction "PR62A") (pintype "bidirectional"))
    (pad "P1" smd circle locked (at -12.4 -2) (size 0.4 0.4) (layers "F.Cu" "F.Paste" "F.Mask")
      (net 746 "unconnected-(U21G-PL62B-PadP1)") (pinfunction "PL62B") (pintype "bidirectional+no_connect"))
    (pad "P2" smd circle locked (at -11.6 -2) (size 0.4 0.4) (layers "F.Cu" "F.Paste" "F.Mask")
      (net 747 "unconnected-(U21G-PL59A-PadP2)") (pinfunction "PL59A") (pintype "bidirectional+no_connect"))
    (pad "P3" smd circle locked (at -10.8 -2) (size 0.4 0.4) (layers "F.Cu" "F.Paste" "F.Mask")
      (net 748 "unconnected-(U21G-PL59B-PadP3)") (pinfunction "PL59B") (pintype "bidirectional+no_connect"))
    (pad "P4" smd circle locked (at -10 -2) (size 0.4 0.4) (layers "F.Cu" "F.Paste" "F.Mask")
      (net 262 "DDR3_CLK-") (pinfunction "PL47B") (pintype "bidirectional"))
    (pad "P5" smd circle locked (at -9.2 -2) (size 0.4 0.4) (layers "F.Cu" "F.Paste" "F.Mask")
      (net 261 "DDR3_CLK+") (pinfunction "PL47A") (pintype "bidirectional"))
    (pad "P6" smd circle locked (at -8.4 -2) (size 0.4 0.4) (layers "F.Cu" "F.Paste" "F.Mask")
      (net 288 "MMC_CLK") (pinfunction "PL44C") (pintype "bidirectional"))
    (pad "P7" smd circle locked (at -7.6 -2) (size 0.4 0.4) (layers "F.Cu" "F.Paste" "F.Mask")
      (net 749 "unconnected-(U21H-PL44D-PadP7)") (pinfunction "PL44D") (pintype "bidirectional+no_connect"))
    (pad "P10" smd circle locked (at -5.2 -2) (size 0.4 0.4) (layers "F.Cu" "F.Paste" "F.Mask")
      (net 2 "VCC3V3") (pinfunction "VCCIO7") (pintype "passive"))
    (pad "P11" smd circle locked (at -4.4 -2) (size 0.4 0.4) (layers "F.Cu" "F.Paste" "F.Mask")
      (net 1 "GND") (pinfunction "GND") (pintype "passive"))
    (pad "P12" smd circle locked (at -3.6 -2) (size 0.4 0.4) (layers "F.Cu" "F.Paste" "F.Mask")
      (net 211 "VCC1V2") (pinfunction "VCC") (pintype "passive"))
    (pad "P13" smd circle locked (at -2.8 -2) (size 0.4 0.4) (layers "F.Cu" "F.Paste" "F.Mask")
      (net 1 "GND") (pinfunction "GND") (pintype "passive"))
    (pad "P14" smd circle locked (at -2 -2) (size 0.4 0.4) (layers "F.Cu" "F.Paste" "F.Mask")
      (net 1 "GND") (pinfunction "GND") (pintype "passive"))
    (pad "P15" smd circle locked (at -1.2 -2) (size 0.4 0.4) (layers "F.Cu" "F.Paste" "F.Mask")
      (net 1 "GND") (pinfunction "GND") (pintype "passive"))
    (pad "P16" smd circle locked (at -0.4 -2) (size 0.4 0.4) (layers "F.Cu" "F.Paste" "F.Mask")
      (net 1 "GND") (pinfunction "GND") (pintype "passive"))
    (pad "P17" smd circle locked (at 0.4 -2) (size 0.4 0.4) (layers "F.Cu" "F.Paste" "F.Mask")
      (net 1 "GND") (pinfunction "GND") (pintype "passive"))
    (pad "P18" smd circle locked (at 1.2 -2) (size 0.4 0.4) (layers "F.Cu" "F.Paste" "F.Mask")
      (net 1 "GND") (pinfunction "GND") (pintype "passive"))
    (pad "P19" smd circle locked (at 2 -2) (size 0.4 0.4) (layers "F.Cu" "F.Paste" "F.Mask")
      (net 1 "GND") (pinfunction "GND") (pintype "passive"))
    (pad "P20" smd circle locked (at 2.8 -2) (size 0.4 0.4) (layers "F.Cu" "F.Paste" "F.Mask")
      (net 1 "GND") (pinfunction "GND") (pintype "passive"))
    (pad "P21" smd circle locked (at 3.6 -2) (size 0.4 0.4) (layers "F.Cu" "F.Paste" "F.Mask")
      (net 211 "VCC1V2") (pinfunction "VCC") (pintype "passive"))
    (pad "P22" smd circle locked (at 4.4 -2) (size 0.4 0.4) (layers "F.Cu" "F.Paste" "F.Mask")
      (net 1 "GND") (pinfunction "GND") (pintype "passive"))
    (pad "P23" smd circle locked (at 5.2 -2) (size 0.4 0.4) (layers "F.Cu" "F.Paste" "F.Mask")
      (net 218 "VCC1V8") (pinfunction "VCCIO2") (pintype "passive"))
    (pad "P26" smd circle locked (at 7.6 -2) (size 0.4 0.4) (layers "F.Cu" "F.Paste" "F.Mask")
      (net 750 "unconnected-(U21D-PR44D-PadP26)") (pinfunction "PR44D") (pintype "bidirectional+no_connect"))
    (pad "P27" smd circle locked (at 8.4 -2) (size 0.4 0.4) (layers "F.Cu" "F.Paste" "F.Mask")
      (net 751 "unconnected-(U21D-PR44C-PadP27)") (pinfunction "PR44C") (pintype "bidirectional+no_connect"))
    (pad "P28" smd circle locked (at 9.2 -2) (size 0.4 0.4) (layers "F.Cu" "F.Paste" "F.Mask")
      (net 334 "ULPI1_CLKO") (pinfunction "PR47A") (pintype "bidirectional"))
    (pad "P29" smd circle locked (at 10 -2) (size 0.4 0.4) (layers "F.Cu" "F.Paste" "F.Mask")
      (net 752 "unconnected-(U21E-PR47B-PadP29)") (pinfunction "PR47B") (pintype "bidirectional+no_connect"))
    (pad "P30" smd circle locked (at 10.8 -2) (size 0.4 0.4) (layers "F.Cu" "F.Paste" "F.Mask")
      (net 330 "ULPI1_RESET") (pinfunction "PR59B") (pintype "bidirectional"))
    (pad "P31" smd circle locked (at 11.6 -2) (size 0.4 0.4) (layers "F.Cu" "F.Paste" "F.Mask")
      (net 332 "ULPI1_DIR") (pinfunction "PR59A") (pintype "bidirectional"))
    (pad "P32" smd circle locked (at 12.4 -2) (size 0.4 0.4) (layers "F.Cu" "F.Paste" "F.Mask")
      (net 333 "ULPI1_STP") (pinfunction "PR62B") (pintype "bidirectional"))
    (pad "R1" smd circle locked (at -12.4 -1.2) (size 0.4 0.4) (layers "F.Cu" "F.Paste" "F.Mask")
      (net 257 "DDR3_CS") (pinfunction "PL65A") (pintype "bidirectional"))
    (pad "R2" smd circle locked (at -11.6 -1.2) (size 0.4 0.4) (layers "F.Cu" "F.Paste" "F.Mask")
      (net 1 "GND") (pinfunction "GND") (pintype "passive"))
    (pad "R3" smd circle locked (at -10.8 -1.2) (size 0.4 0.4) (layers "F.Cu" "F.Paste" "F.Mask")
      (net 753 "unconnected-(U21G-PL59C-PadR3)") (pinfunction "PL59C") (pintype "bidirectional+no_connect"))
    (pad "R4" smd circle locked (at -10 -1.2) (size 0.4 0.4) (layers "F.Cu" "F.Paste" "F.Mask")
      (net 239 "DDR3_A9") (pinfunction "PL53A") (pintype "bidirectional"))
    (pad "R5" smd circle locked (at -9.2 -1.2) (size 0.4 0.4) (layers "F.Cu" "F.Paste" "F.Mask")
      (net 1 "GND") (pinfunction "GND") (pintype "passive"))
    (pad "R6" smd circle locked (at -8.4 -1.2) (size 0.4 0.4) (layers "F.Cu" "F.Paste" "F.Mask")
      (net 245 "DDR3_A4") (pinfunction "PL50A") (pintype "bidirectional"))
  )
)
